FILE_TYPE = MACRO_DRAWING;
SET COLOR_WIRE YELLOW;
SET COLOR_PROP ORANGE;
SET COLOR_DOT WHITE;
SET COLOR_ARC YELLOW;
SET COLOR_BODY GREEN;
SET COLOR_NOTE PURPLE;
SET PROP_DISPLAY VALUE;
SET PAGE_NUMBER P25;
SET PATH_NUMBER P176;
FORCEADD UNIVERSAL_POWER..1
(350 4100);
FORCEPROP 3 LASTPIN (350 4050) SIG_NAME P3V3_AUX\g
J 0
(360 4060);
DISPLAY 0.659574 (360 4060);
PAINT MONO (360 4060);
DISPLAY INVISIBLE (360 4060);
FORCEPROP 1 LAST HDL_POWER P3V3_AUX
J 1
(350 4150);
DISPLAY 0.702128 (350 4150);
PAINT GREEN (350 4150);
FORCEPROP 1 LAST PATH I135
J 0
(400 4125);
DISPLAY 0.872340 (400 4125);
PAINT AQUA (400 4125);
DISPLAY INVISIBLE (400 4125);
FORCEPROP 2 LAST CDS_LIB logical_power
J 0
(350 4100);
DISPLAY INVISIBLE (350 4100);
FORCEADD OFFPAGE..2
(1175 3750);
FORCEPROP 2 LAST $XR0 13 
J 0
(1364 3750);
DISPLAY 0.638298 (1364 3750);
PAINT MONO (1364 3750);
FORCEPROP 2 LAST $XR1 25 
J 0
(1454 3750);
DISPLAY 0.638298 (1454 3750);
PAINT MONO (1454 3750);
FORCEPROP 2 LAST CDS_LIB standard
J 0
(1175 3750);
DISPLAY INVISIBLE (1175 3750);
FORCEPROP 2 LAST PATH I137
J 0
(1350 3825);
DISPLAY 0.680851 (1350 3825);
DISPLAY INVISIBLE (1350 3825);
FORCEPROP 1 LAST COMMENT_BODY TRUE
J 0
(1130 3655);
DISPLAY 0.872340 (1130 3655);
PAINT GREEN (1130 3655);
DISPLAY INVISIBLE (1130 3655);
FORCEPROP 1 LAST OFFPAGE TRUE
J 0
(1500 3625);
DISPLAY 0.872340 (1500 3625);
DISPLAY INVISIBLE (1500 3625);
FORCEADD 74LVC1G74DP..1
(3075 3500);
FORCEPROP 1 LAST PART_NUMBER AL1G0074K01
J 0
(2875 3864);
DISPLAY 0.723404 (2875 3864);
PAINT GREEN (2875 3864);
FORCEPROP 2 LAST VALUE 74LVC1G74DP
J 0
(2875 3975);
DISPLAY 0.680851 (2875 3975);
FORCEPROP 1 LAST MATERIAL IC
J 0
(2875 3809);
DISPLAY 0.723404 (2875 3809);
PAINT GREEN (2875 3809);
FORCEPROP 2 LAST PART_TYPE SMLF
J 0
(2875 4025);
DISPLAY 0.680851 (2875 4025);
FORCEPROP 1 LAST CDS_LMAN_SYM_OUTLINE -200,300,200,-300
J 0
(3075 3500);
DISPLAY 0.468085 (3075 3500);
PAINT GREEN (3075 3500);
DISPLAY INVISIBLE (3075 3500);
FORCEPROP 1 LAST NEEDS_NO_SIZE TRUE
J 0
(3075 3500);
DISPLAY 0.723404 (3075 3500);
PAINT GREEN (3075 3500);
DISPLAY INVISIBLE (3075 3500);
FORCEPROP 1 LAST PATH I138
J 0
(3075 3500);
DISPLAY 0.723404 (3075 3500);
PAINT GREEN (3075 3500);
DISPLAY INVISIBLE (3075 3500);
FORCEPROP 2 LAST CDS_LIB pure_quanta
J 0
(3075 3500);
DISPLAY INVISIBLE (3075 3500);
FORCEPROP 1 LAST $LOCATION U54
J 0
(2875 3927);
DISPLAY 0.723404 (2875 3927);
PAINT GREEN (2875 3927);
FORCEPROP 0 LASTPIN (2725 3500) $PN 1
J 2
(2715 3510);
DISPLAY 0.680851 (2715 3510);
PAINT MONO (2715 3510);
FORCEPROP 0 LASTPIN (2725 3600) $PN 2
J 2
(2715 3610);
DISPLAY 0.680851 (2715 3610);
PAINT MONO (2715 3610);
FORCEPROP 0 LASTPIN (3425 3250) $PN 4
J 0
(3435 3260);
DISPLAY 0.680851 (3435 3260);
PAINT MONO (3435 3260);
FORCEPROP 0 LASTPIN (3425 3650) $PN 5
J 0
(3435 3660);
DISPLAY 0.680851 (3435 3660);
PAINT MONO (3435 3660);
FORCEPROP 0 LASTPIN (3425 3550) $PN 3
J 0
(3435 3560);
DISPLAY 0.680851 (3435 3560);
PAINT MONO (3435 3560);
FORCEPROP 0 LASTPIN (2725 3300) $PN 6
J 2
(2715 3310);
DISPLAY 0.680851 (2715 3310);
PAINT MONO (2715 3310);
FORCEPROP 0 LASTPIN (2725 3400) $PN 7
J 2
(2715 3410);
DISPLAY 0.680851 (2715 3410);
PAINT MONO (2715 3410);
FORCEPROP 0 LASTPIN (2725 3750) $PN 8
J 2
(2715 3760);
DISPLAY 0.680851 (2715 3760);
PAINT MONO (2715 3760);
FORCEPROP 0 LAST CDS_LOCATION U54
J 0
(2875 4075);
DISPLAY 0.680851 (2875 4075);
DISPLAY INVISIBLE (2875 4075);
FORCEPROP 0 LAST $SEC 1
J 0
(2875 4075);
DISPLAY 0.680851 (2875 4075);
PAINT MONO (2875 4075);
DISPLAY INVISIBLE (2875 4075);
FORCEPROP 0 LAST CDS_SEC 1
J 0
(2875 4075);
DISPLAY 0.680851 (2875 4075);
DISPLAY INVISIBLE (2875 4075);
FORCEADD OFFPAGE..4
R 2
(1675 3400);
FORCEPROP 2 LAST $XR1 25 
J 0
(1454 3364);
DISPLAY 0.638298 (1454 3364);
PAINT MONO (1454 3364);
FORCEPROP 2 LAST $XR0 13 
J 0
(1454 3400);
DISPLAY 0.638298 (1454 3400);
PAINT MONO (1454 3400);
FORCEPROP 2 LAST CDS_LIB standard
J 2
(1675 3400);
DISPLAY INVISIBLE (1675 3400);
FORCEPROP 1 LAST OFFPAGE TRUE
J 2
(1350 3275);
DISPLAY 0.872340 (1350 3275);
PAINT GREEN (1350 3275);
DISPLAY INVISIBLE (1350 3275);
FORCEPROP 1 LAST COMMENT_BODY TRUE
J 2
(1700 3300);
DISPLAY 0.872340 (1700 3300);
PAINT PEACH (1700 3300);
DISPLAY INVISIBLE (1700 3300);
FORCEPROP 2 LAST PATH I139
J 2
(1475 3450);
DISPLAY 0.680851 (1475 3450);
DISPLAY INVISIBLE (1475 3450);
FORCEADD OFFPAGE..4
R 2
(1675 3300);
FORCEPROP 2 LAST $XR0 15 
J 0
(1454 3300);
DISPLAY 0.638298 (1454 3300);
PAINT MONO (1454 3300);
FORCEPROP 2 LAST CDS_LIB standard
J 0
(1675 3300);
DISPLAY INVISIBLE (1675 3300);
FORCEPROP 2 LAST PATH I140
J 0
(1725 3375);
DISPLAY 0.680851 (1725 3375);
DISPLAY INVISIBLE (1725 3375);
FORCEPROP 1 LAST OFFPAGE TRUE
J 2
(1350 3175);
DISPLAY 0.872340 (1350 3175);
PAINT GREEN (1350 3175);
DISPLAY INVISIBLE (1350 3175);
FORCEPROP 1 LAST COMMENT_BODY TRUE
J 2
(1700 3200);
DISPLAY 0.872340 (1700 3200);
PAINT PEACH (1700 3200);
DISPLAY INVISIBLE (1700 3200);
FORCEADD Q_RES..1
(2000 3600);
FORCEPROP 1 LAST PART_NUMBER CS00002JB13
J 0
(1750 3725);
DISPLAY 0.510638 (1750 3725);
PAINT WHITE (1750 3725);
FORCEPROP 1 LAST VALUE 0
J 2
(2125 3600);
DISPLAY 0.510638 (2125 3600);
PAINT SKYBLUE (2125 3600);
FORCEPROP 1 LAST PACK_TYPE 0402LF
J 0
(2100 3650);
DISPLAY 0.510638 (2100 3650);
PAINT SKYBLUE (2100 3650);
FORCEPROP 1 LAST TOLERANCE 5%
J 0
(2375 3650);
DISPLAY 0.510638 (2375 3650);
PAINT SKYBLUE (2375 3650);
FORCEPROP 1 LAST WATTAGE 1/16W
J 2
(1875 3650);
DISPLAY 0.510638 (1875 3650);
PAINT SKYBLUE (1875 3650);
FORCEPROP 1 LAST MATERIAL CHIP
J 0
(1825 3600);
DISPLAY 0.510638 (1825 3600);
PAINT SKYBLUE (1825 3600);
FORCEPROP 2 LAST CDS_LIB pure_quanta
J 0
(2000 3600);
DISPLAY INVISIBLE (2000 3600);
FORCEPROP 1 LAST PATH I142
J 0
(1950 3750);
DISPLAY 0.978723 (1950 3750);
PAINT WHITE (1950 3750);
DISPLAY INVISIBLE (1950 3750);
FORCEPROP 1 LAST $LOCATION R182
J 0
(1600 3600);
DISPLAY 0.702128 (1600 3600);
PAINT YELLOW (1600 3600);
FORCEPROP 1 LASTPIN (1900 3600) $PN 1
J 0
(1912 3612);
DISPLAY 0.787234 (1912 3612);
PAINT MONO (1912 3612);
FORCEPROP 1 LASTPIN (2100 3600) $PN 2
J 0
(2062 3612);
DISPLAY 0.787234 (2062 3612);
PAINT MONO (2062 3612);
FORCEPROP 0 LAST CDS_LOCATION R182
J 0
(1750 3750);
DISPLAY 0.680851 (1750 3750);
DISPLAY INVISIBLE (1750 3750);
FORCEPROP 0 LAST $SEC 1
J 0
(1750 3750);
DISPLAY 0.680851 (1750 3750);
PAINT MONO (1750 3750);
DISPLAY INVISIBLE (1750 3750);
FORCEPROP 0 LAST CDS_SEC 1
J 0
(1750 3750);
DISPLAY 0.680851 (1750 3750);
DISPLAY INVISIBLE (1750 3750);
FORCEADD Q_RES..1
(2000 3500);
FORCEPROP 1 LAST MATERIAL CHIP
J 0
(1825 3500);
DISPLAY 0.510638 (1825 3500);
PAINT SKYBLUE (1825 3500);
FORCEPROP 1 LAST VALUE 0
J 2
(2125 3500);
DISPLAY 0.510638 (2125 3500);
PAINT SKYBLUE (2125 3500);
FORCEPROP 1 LAST PART_NUMBER CS00002JB13
J 0
(1750 3625);
DISPLAY 0.510638 (1750 3625);
PAINT WHITE (1750 3625);
DISPLAY INVISIBLE (1750 3625);
FORCEPROP 1 LAST PATH I143
J 0
(1950 3650);
DISPLAY 0.978723 (1950 3650);
PAINT WHITE (1950 3650);
DISPLAY INVISIBLE (1950 3650);
FORCEPROP 2 LAST CDS_LIB pure_quanta
J 0
(2000 3500);
DISPLAY INVISIBLE (2000 3500);
FORCEPROP 1 LAST PACK_TYPE 0402LF
J 0
(2100 3550);
DISPLAY 0.510638 (2100 3550);
PAINT SKYBLUE (2100 3550);
DISPLAY INVISIBLE (2100 3550);
FORCEPROP 1 LAST WATTAGE 1/16W
J 2
(1875 3550);
DISPLAY 0.510638 (1875 3550);
PAINT SKYBLUE (1875 3550);
DISPLAY INVISIBLE (1875 3550);
FORCEPROP 1 LAST TOLERANCE 5%
J 0
(2375 3550);
DISPLAY 0.510638 (2375 3550);
PAINT SKYBLUE (2375 3550);
DISPLAY INVISIBLE (2375 3550);
FORCEPROP 1 LAST $LOCATION R545
J 0
(1600 3500);
DISPLAY 0.808511 (1600 3500);
FORCEPROP 1 LASTPIN (1900 3500) $PN 1
J 0
(1912 3512);
DISPLAY 0.787234 (1912 3512);
PAINT MONO (1912 3512);
FORCEPROP 1 LASTPIN (2100 3500) $PN 2
J 0
(2062 3512);
DISPLAY 0.787234 (2062 3512);
PAINT MONO (2062 3512);
FORCEPROP 0 LAST CDS_LOCATION R545
J 0
(1950 3600);
DISPLAY 0.680851 (1950 3600);
DISPLAY INVISIBLE (1950 3600);
FORCEPROP 0 LAST $SEC 1
J 0
(1950 3600);
DISPLAY 0.680851 (1950 3600);
PAINT MONO (1950 3600);
DISPLAY INVISIBLE (1950 3600);
FORCEPROP 0 LAST CDS_SEC 1
J 0
(1950 3600);
DISPLAY 0.680851 (1950 3600);
DISPLAY INVISIBLE (1950 3600);
FORCEADD UNIVERSAL_GND..1
R 2
(1350 3425);
FORCEPROP 3 LASTPIN (1350 3475) SIG_NAME GND\g
J 0
(1360 3485);
DISPLAY 0.659574 (1360 3485);
PAINT MONO (1360 3485);
DISPLAY INVISIBLE (1360 3485);
FORCEPROP 2 LAST CDS_LIB logical_power
R 3
J 0
(1350 3425);
DISPLAY INVISIBLE (1350 3425);
FORCEPROP 1 LAST PATH I144
J 2
(1275 3425);
DISPLAY 0.872340 (1275 3425);
PAINT AQUA (1275 3425);
DISPLAY INVISIBLE (1275 3425);
FORCEPROP 1 LAST HDL_POWER GND
J 1
(1325 3350);
DISPLAY 0.702128 (1325 3350);
PAINT GREEN (1325 3350);
DISPLAY INVISIBLE (1325 3350);
FORCEADD UNIVERSAL_POWER..1
(2375 4225);
FORCEPROP 3 LASTPIN (2375 4175) SIG_NAME P3V3_AUX\g
J 0
(2385 4185);
DISPLAY 0.659574 (2385 4185);
PAINT MONO (2385 4185);
DISPLAY INVISIBLE (2385 4185);
FORCEPROP 1 LAST HDL_POWER P3V3_AUX
J 1
(2375 4275);
DISPLAY 0.702128 (2375 4275);
PAINT GREEN (2375 4275);
FORCEPROP 2 LAST CDS_LIB logical_power
J 0
(2375 4225);
DISPLAY INVISIBLE (2375 4225);
FORCEPROP 1 LAST PATH I145
J 0
(2425 4250);
DISPLAY 0.872340 (2425 4250);
PAINT AQUA (2425 4250);
DISPLAY INVISIBLE (2425 4250);
FORCEADD Q_CAP..1
(2375 4000);
FORCEPROP 1 LAST VALUE 0.1UF
J 0
(2425 4050);
DISPLAY 0.510638 (2425 4050);
PAINT SKYBLUE (2425 4050);
FORCEPROP 1 LAST PACK_TYPE 0402
J 0
(2425 3800);
DISPLAY 0.510638 (2425 3800);
PAINT SKYBLUE (2425 3800);
FORCEPROP 1 LAST VOLTAGE 25V
J 0
(2425 4000);
DISPLAY 0.510638 (2425 4000);
PAINT SKYBLUE (2425 4000);
FORCEPROP 1 LAST PART_NUMBER CH4104K1B00
J 0
(2425 3850);
DISPLAY 0.510638 (2425 3850);
PAINT WHITE (2425 3850);
FORCEPROP 1 LAST MATERIAL X7R
J 0
(2425 3900);
DISPLAY 0.510638 (2425 3900);
PAINT RED (2425 3900);
FORCEPROP 1 LAST TOLERANCE 10%
J 0
(2425 3950);
DISPLAY 0.510638 (2425 3950);
PAINT SKYBLUE (2425 3950);
FORCEPROP 2 LAST CDS_LIB pure_quanta
J 0
(2375 4000);
DISPLAY INVISIBLE (2375 4000);
FORCEPROP 1 LAST PATH I146
J 0
(2425 4150);
DISPLAY 0.978723 (2425 4150);
PAINT WHITE (2425 4150);
DISPLAY INVISIBLE (2425 4150);
FORCEPROP 1 LAST $LOCATION C312
J 0
(2425 4100);
DISPLAY 0.702128 (2425 4100);
PAINT YELLOW (2425 4100);
FORCEPROP 1 LASTPIN (2375 4100) $PN 1
J 0
(2385 4080);
DISPLAY 0.787234 (2385 4080);
PAINT MONO (2385 4080);
FORCEPROP 1 LASTPIN (2375 3900) $PN 2
J 0
(2385 3880);
DISPLAY 0.787234 (2385 3880);
PAINT MONO (2385 3880);
FORCEPROP 0 LAST CDS_LOCATION C312
J 0
(2425 4150);
DISPLAY 0.680851 (2425 4150);
DISPLAY INVISIBLE (2425 4150);
FORCEPROP 0 LAST $SEC 1
J 0
(2425 4150);
DISPLAY 0.680851 (2425 4150);
PAINT MONO (2425 4150);
DISPLAY INVISIBLE (2425 4150);
FORCEPROP 0 LAST CDS_SEC 1
J 0
(2425 4150);
DISPLAY 0.680851 (2425 4150);
DISPLAY INVISIBLE (2425 4150);
FORCEADD UNIVERSAL_GND..1
R 2
(2375 3775);
FORCEPROP 3 LASTPIN (2375 3825) SIG_NAME GND\g
J 0
(2385 3835);
DISPLAY 0.659574 (2385 3835);
PAINT MONO (2385 3835);
DISPLAY INVISIBLE (2385 3835);
FORCEPROP 2 LAST CDS_LIB logical_power
J 0
(2375 3775);
DISPLAY INVISIBLE (2375 3775);
FORCEPROP 1 LAST PATH I147
J 2
(2300 3775);
DISPLAY 0.872340 (2300 3775);
PAINT AQUA (2300 3775);
DISPLAY INVISIBLE (2300 3775);
FORCEPROP 1 LAST HDL_POWER GND
J 1
(2350 3700);
DISPLAY 0.702128 (2350 3700);
PAINT GREEN (2350 3700);
DISPLAY INVISIBLE (2350 3700);
FORCEADD Q_RES..2
(5000 3150);
FORCEPROP 1 LAST PART_NUMBER CS00002JB13
J 0
(4675 3050);
DISPLAY 0.638298 (4675 3050);
FORCEPROP 1 LAST PACK_TYPE 0402LF
J 0
(4675 3000);
DISPLAY 0.638298 (4675 3000);
FORCEPROP 1 LAST WATTAGE 1/16W
J 0
(4675 3150);
DISPLAY 0.638298 (4675 3150);
FORCEPROP 1 LAST MATERIAL CHIP
J 0
(4675 3100);
DISPLAY 0.638298 (4675 3100);
FORCEPROP 1 LAST VALUE 0
J 0
(4680 3250);
DISPLAY 0.638298 (4680 3250);
FORCEPROP 1 LAST TOLERANCE 5%
J 0
(4680 3200);
DISPLAY 0.638298 (4680 3200);
FORCEPROP 1 LAST PATH I149
J 0
(5050 3325);
DISPLAY 0.978723 (5050 3325);
PAINT WHITE (5050 3325);
DISPLAY INVISIBLE (5050 3325);
FORCEPROP 2 LAST CDS_LIB pure_quanta
J 0
(5000 3150);
DISPLAY INVISIBLE (5000 3150);
FORCEPROP 1 LAST $LOCATION R560
J 0
(4680 3300);
DISPLAY 0.638298 (4680 3300);
FORCEPROP 1 LASTPIN (5000 3250) $PN 1
J 0
(5005 3212);
DISPLAY 0.787234 (5005 3212);
PAINT MONO (5005 3212);
FORCEPROP 1 LASTPIN (5000 3050) $PN 2
J 0
(5005 3060);
DISPLAY 0.787234 (5005 3060);
PAINT MONO (5005 3060);
FORCEPROP 0 LAST CDS_LOCATION R560
J 0
(4700 3350);
DISPLAY 0.680851 (4700 3350);
DISPLAY INVISIBLE (4700 3350);
FORCEPROP 0 LAST $SEC 1
J 0
(4700 3350);
DISPLAY 0.680851 (4700 3350);
PAINT MONO (4700 3350);
DISPLAY INVISIBLE (4700 3350);
FORCEPROP 0 LAST CDS_SEC 1
J 0
(4700 3350);
DISPLAY 0.680851 (4700 3350);
DISPLAY INVISIBLE (4700 3350);
FORCEADD SN74LVC1G14DCKR..1
R 2
(4275 2600);
FORCEPROP 1 LAST MATERIAL IC
J 2
(4400 2760);
DISPLAY 0.723404 (4400 2760);
PAINT GREEN (4400 2760);
FORCEPROP 2 LAST VALUE SN74LVC1G14DCKR
J 2
(4550 2950);
DISPLAY 0.680851 (4550 2950);
FORCEPROP 2 LAST PACK_TYPE SMLF
J 2
(4550 2900);
DISPLAY 0.680851 (4550 2900);
FORCEPROP 1 LAST PART_NUMBER AL001G14017
J 2
(4550 2810);
DISPLAY 0.723404 (4550 2810);
PAINT GREEN (4550 2810);
FORCEPROP 1 LAST NEEDS_NO_SIZE TRUE
J 2
(4275 2600);
DISPLAY 0.468085 (4275 2600);
PAINT GREEN (4275 2600);
DISPLAY INVISIBLE (4275 2600);
FORCEPROP 1 LAST PATH I150
J 2
(4175 2755);
DISPLAY 0.723404 (4175 2755);
PAINT GREEN (4175 2755);
DISPLAY INVISIBLE (4175 2755);
FORCEPROP 2 LAST CDS_LIB pure_quanta
J 2
(4275 2600);
DISPLAY INVISIBLE (4275 2600);
FORCEPROP 1 LAST $LOCATION U55
J 2
(4550 2855);
DISPLAY 0.723404 (4550 2855);
PAINT GREEN (4550 2855);
FORCEPROP 0 LASTPIN (4450 2600) $PN 2
J 0
(4460 2610);
DISPLAY 0.680851 (4460 2610);
PAINT MONO (4460 2610);
FORCEPROP 0 LASTPIN (4100 2500) $PN 3
J 2
(4090 2510);
DISPLAY 0.680851 (4090 2510);
PAINT MONO (4090 2510);
FORCEPROP 0 LASTPIN (4450 2500) $PN 1
J 0
(4460 2510);
DISPLAY 0.680851 (4460 2510);
PAINT MONO (4460 2510);
FORCEPROP 0 LASTPIN (4100 2700) $PN 5
J 2
(4090 2710);
DISPLAY 0.680851 (4090 2710);
PAINT MONO (4090 2710);
FORCEPROP 0 LASTPIN (4100 2600) $PN 4
J 2
(4090 2610);
DISPLAY 0.680851 (4090 2610);
PAINT MONO (4090 2610);
FORCEPROP 0 LAST CDS_LOCATION U55
J 0
(4550 3000);
DISPLAY 0.680851 (4550 3000);
DISPLAY INVISIBLE (4550 3000);
FORCEPROP 0 LAST $SEC 1
J 0
(4550 3000);
DISPLAY 0.680851 (4550 3000);
PAINT MONO (4550 3000);
DISPLAY INVISIBLE (4550 3000);
FORCEPROP 0 LAST CDS_SEC 1
J 0
(4550 3000);
DISPLAY 0.680851 (4550 3000);
DISPLAY INVISIBLE (4550 3000);
FORCEADD OFFPAGE..2
R 2
(1975 2600);
FORCEPROP 2 LAST $XR0 13 
J 0
(1721 2600);
DISPLAY 0.638298 (1721 2600);
PAINT MONO (1721 2600);
FORCEPROP 2 LAST CDS_LIB standard
J 2
(1975 2600);
DISPLAY INVISIBLE (1975 2600);
FORCEPROP 2 LAST PATH I152
J 2
(1800 2675);
DISPLAY 0.680851 (1800 2675);
DISPLAY INVISIBLE (1800 2675);
FORCEPROP 1 LAST COMMENT_BODY TRUE
J 2
(2020 2505);
DISPLAY 0.872340 (2020 2505);
PAINT GREEN (2020 2505);
DISPLAY INVISIBLE (2020 2505);
FORCEPROP 1 LAST OFFPAGE TRUE
J 2
(1650 2475);
DISPLAY 0.872340 (1650 2475);
DISPLAY INVISIBLE (1650 2475);
FORCEADD UNIVERSAL_POWER..1
(3675 3275);
FORCEPROP 3 LASTPIN (3675 3225) SIG_NAME P3V3_AUX\g
J 0
(3685 3235);
DISPLAY 0.659574 (3685 3235);
PAINT MONO (3685 3235);
DISPLAY INVISIBLE (3685 3235);
FORCEPROP 1 LAST HDL_POWER P3V3_AUX
J 1
(3675 3325);
DISPLAY 0.702128 (3675 3325);
PAINT GREEN (3675 3325);
FORCEPROP 1 LAST PATH I153
J 0
(3725 3300);
DISPLAY 0.872340 (3725 3300);
PAINT AQUA (3725 3300);
DISPLAY INVISIBLE (3725 3300);
FORCEPROP 2 LAST CDS_LIB logical_power
J 0
(3675 3275);
DISPLAY INVISIBLE (3675 3275);
FORCEADD Q_CAP..1
(3675 3000);
FORCEPROP 1 LAST VOLTAGE 25V
J 0
(3725 3000);
DISPLAY 0.510638 (3725 3000);
PAINT SKYBLUE (3725 3000);
FORCEPROP 1 LAST VALUE 0.1UF
J 0
(3725 3050);
DISPLAY 0.510638 (3725 3050);
PAINT SKYBLUE (3725 3050);
FORCEPROP 1 LAST MATERIAL X7R
J 0
(3725 2900);
DISPLAY 0.510638 (3725 2900);
PAINT RED (3725 2900);
FORCEPROP 1 LAST TOLERANCE 10%
J 0
(3725 2950);
DISPLAY 0.510638 (3725 2950);
PAINT SKYBLUE (3725 2950);
FORCEPROP 1 LAST PART_NUMBER CH4104K1B00
J 0
(3725 2850);
DISPLAY 0.510638 (3725 2850);
PAINT WHITE (3725 2850);
FORCEPROP 1 LAST PACK_TYPE 0402
J 0
(3725 2800);
DISPLAY 0.510638 (3725 2800);
PAINT SKYBLUE (3725 2800);
FORCEPROP 2 LAST CDS_LIB pure_quanta
J 0
(3675 3000);
DISPLAY INVISIBLE (3675 3000);
FORCEPROP 1 LAST PATH I154
J 0
(3725 3150);
DISPLAY 0.978723 (3725 3150);
PAINT WHITE (3725 3150);
DISPLAY INVISIBLE (3725 3150);
FORCEPROP 1 LAST $LOCATION C313
J 0
(3725 3100);
DISPLAY 0.702128 (3725 3100);
PAINT YELLOW (3725 3100);
FORCEPROP 1 LASTPIN (3675 3100) $PN 1
J 0
(3685 3080);
DISPLAY 0.787234 (3685 3080);
PAINT MONO (3685 3080);
FORCEPROP 1 LASTPIN (3675 2900) $PN 2
J 0
(3685 2880);
DISPLAY 0.787234 (3685 2880);
PAINT MONO (3685 2880);
FORCEPROP 0 LAST CDS_LOCATION C313
J 0
(3725 3150);
DISPLAY 0.680851 (3725 3150);
DISPLAY INVISIBLE (3725 3150);
FORCEPROP 0 LAST $SEC 1
J 0
(3725 3150);
DISPLAY 0.680851 (3725 3150);
PAINT MONO (3725 3150);
DISPLAY INVISIBLE (3725 3150);
FORCEPROP 0 LAST CDS_SEC 1
J 0
(3725 3150);
DISPLAY 0.680851 (3725 3150);
DISPLAY INVISIBLE (3725 3150);
FORCEADD UNIVERSAL_GND..1
R 2
(3675 2825);
FORCEPROP 3 LASTPIN (3675 2875) SIG_NAME GND\g
J 0
(3685 2885);
DISPLAY 0.659574 (3685 2885);
PAINT MONO (3685 2885);
DISPLAY INVISIBLE (3685 2885);
FORCEPROP 1 LAST HDL_POWER GND
J 1
(3650 2750);
DISPLAY 0.702128 (3650 2750);
PAINT GREEN (3650 2750);
DISPLAY INVISIBLE (3650 2750);
FORCEPROP 1 LAST PATH I155
J 2
(3600 2825);
DISPLAY 0.872340 (3600 2825);
PAINT AQUA (3600 2825);
DISPLAY INVISIBLE (3600 2825);
FORCEPROP 2 LAST CDS_LIB logical_power
J 0
(3675 2825);
DISPLAY INVISIBLE (3675 2825);
FORCEADD Q_RES..2
(3100 2925);
FORCEPROP 1 LAST MATERIAL EMPTY
J 0
(3125 2775);
DISPLAY 0.510638 (3125 2775);
PAINT BROWN (3125 2775);
FORCEPROP 1 LAST TOLERANCE 1%
J 0
(3150 2900);
DISPLAY 0.510638 (3150 2900);
PAINT SKYBLUE (3150 2900);
FORCEPROP 1 LAST VALUE 4.7K
J 0
(3150 2950);
DISPLAY 0.510638 (3150 2950);
PAINT SKYBLUE (3150 2950);
FORCEPROP 2 LAST CDS_LIB pure_quanta
J 0
(3100 2925);
DISPLAY INVISIBLE (3100 2925);
FORCEPROP 1 LAST PATH I156
J 0
(3150 3100);
DISPLAY 0.978723 (3150 3100);
PAINT WHITE (3150 3100);
DISPLAY INVISIBLE (3150 3100);
FORCEPROP 1 LAST PART_NUMBER CS24702FB10
J 0
(3140 2800);
DISPLAY 0.510638 (3140 2800);
PAINT WHITE (3140 2800);
DISPLAY INVISIBLE (3140 2800);
FORCEPROP 1 LAST WATTAGE 1/16W
J 0
(3140 2900);
DISPLAY 0.510638 (3140 2900);
PAINT SKYBLUE (3140 2900);
DISPLAY INVISIBLE (3140 2900);
FORCEPROP 1 LAST PACK_TYPE 0402LF
J 0
(3140 2750);
DISPLAY 0.510638 (3140 2750);
PAINT SKYBLUE (3140 2750);
DISPLAY INVISIBLE (3140 2750);
FORCEPROP 1 LAST $LOCATION R554
J 0
(3145 3050);
DISPLAY 0.978723 (3145 3050);
FORCEPROP 1 LASTPIN (3100 3025) $PN 1
J 0
(3105 2987);
DISPLAY 0.787234 (3105 2987);
PAINT MONO (3105 2987);
FORCEPROP 1 LASTPIN (3100 2825) $PN 2
J 0
(3105 2835);
DISPLAY 0.787234 (3105 2835);
PAINT MONO (3105 2835);
FORCEPROP 0 LAST CDS_LOCATION R554
J 0
(3150 3100);
DISPLAY 0.680851 (3150 3100);
DISPLAY INVISIBLE (3150 3100);
FORCEPROP 0 LAST $SEC 1
J 0
(3150 3100);
DISPLAY 0.680851 (3150 3100);
PAINT MONO (3150 3100);
DISPLAY INVISIBLE (3150 3100);
FORCEPROP 0 LAST CDS_SEC 1
J 0
(3150 3100);
DISPLAY 0.680851 (3150 3100);
DISPLAY INVISIBLE (3150 3100);
FORCEADD UNIVERSAL_GND..1
R 2
(3450 3175);
FORCEPROP 3 LASTPIN (3450 3225) SIG_NAME GND\g
J 0
(3460 3235);
DISPLAY 0.659574 (3460 3235);
PAINT MONO (3460 3235);
DISPLAY INVISIBLE (3460 3235);
FORCEPROP 2 LAST CDS_LIB logical_power
J 0
(3450 3175);
DISPLAY INVISIBLE (3450 3175);
FORCEPROP 1 LAST PATH I157
J 2
(3375 3175);
DISPLAY 0.872340 (3375 3175);
PAINT AQUA (3375 3175);
DISPLAY INVISIBLE (3375 3175);
FORCEPROP 1 LAST HDL_POWER GND
J 1
(3425 3100);
DISPLAY 0.702128 (3425 3100);
PAINT GREEN (3425 3100);
DISPLAY INVISIBLE (3425 3100);
FORCEADD UNIVERSAL_GND..1
R 2
(3850 2425);
FORCEPROP 3 LASTPIN (3850 2475) SIG_NAME GND\g
J 0
(3860 2485);
DISPLAY 0.659574 (3860 2485);
PAINT MONO (3860 2485);
DISPLAY INVISIBLE (3860 2485);
FORCEPROP 1 LAST HDL_POWER GND
J 1
(3825 2350);
DISPLAY 0.702128 (3825 2350);
PAINT GREEN (3825 2350);
DISPLAY INVISIBLE (3825 2350);
FORCEPROP 1 LAST PATH I158
J 2
(3775 2425);
DISPLAY 0.872340 (3775 2425);
PAINT AQUA (3775 2425);
DISPLAY INVISIBLE (3775 2425);
FORCEPROP 2 LAST CDS_LIB logical_power
J 0
(3850 2425);
DISPLAY INVISIBLE (3850 2425);
FORCEADD OFFPAGE..2
R 2
(2075 1900);
FORCEPROP 2 LAST $XR0 21 
J 0
(1851 1900);
DISPLAY 0.638298 (1851 1900);
PAINT MONO (1851 1900);
FORCEPROP 1 LAST COMMENT_BODY TRUE
J 2
(2120 1805);
DISPLAY 0.872340 (2120 1805);
PAINT GREEN (2120 1805);
DISPLAY INVISIBLE (2120 1805);
FORCEPROP 1 LAST OFFPAGE TRUE
J 2
(1750 1775);
DISPLAY 0.872340 (1750 1775);
DISPLAY INVISIBLE (1750 1775);
FORCEPROP 2 LAST PATH I162
J 0
(2125 1975);
DISPLAY 0.680851 (2125 1975);
DISPLAY INVISIBLE (2125 1975);
FORCEPROP 2 LAST CDS_LIB standard
J 0
(2075 1900);
DISPLAY INVISIBLE (2075 1900);
FORCEADD OFFPAGE..2
R 2
(2075 1825);
FORCEPROP 2 LAST $XR0 21 
J 0
(1851 1825);
DISPLAY 0.638298 (1851 1825);
PAINT MONO (1851 1825);
FORCEPROP 1 LAST OFFPAGE TRUE
J 2
(1750 1700);
DISPLAY 0.872340 (1750 1700);
DISPLAY INVISIBLE (1750 1700);
FORCEPROP 1 LAST COMMENT_BODY TRUE
J 2
(2120 1730);
DISPLAY 0.872340 (2120 1730);
PAINT GREEN (2120 1730);
DISPLAY INVISIBLE (2120 1730);
FORCEPROP 2 LAST PATH I163
J 0
(2125 1900);
DISPLAY 0.680851 (2125 1900);
DISPLAY INVISIBLE (2125 1900);
FORCEPROP 2 LAST CDS_LIB standard
J 0
(2075 1825);
DISPLAY INVISIBLE (2075 1825);
FORCEADD UNIVERSAL_POWER..1
(3900 1725);
FORCEPROP 3 LASTPIN (3900 1675) SIG_NAME P3V3_AUX\g
J 0
(3910 1685);
DISPLAY 0.659574 (3910 1685);
PAINT MONO (3910 1685);
DISPLAY INVISIBLE (3910 1685);
FORCEPROP 1 LAST HDL_POWER P3V3_AUX
J 1
(3900 1775);
DISPLAY 0.702128 (3900 1775);
PAINT GREEN (3900 1775);
FORCEPROP 2 LAST CDS_LIB logical_power
J 0
(3900 1725);
DISPLAY INVISIBLE (3900 1725);
FORCEPROP 1 LAST PATH I166
J 0
(3950 1750);
DISPLAY 0.872340 (3950 1750);
PAINT AQUA (3950 1750);
DISPLAY INVISIBLE (3950 1750);
FORCEADD SCONN3_212H9103GBR1..1
(4500 1250);
FORCEPROP 1 LAST PART_NUMBER DFHD03MS161
J 0
(4450 1450);
DISPLAY 0.723404 (4450 1450);
PAINT GREEN (4450 1450);
FORCEPROP 2 LAST VALUE SCONN3_212-H91-03GBR1
J 0
(4450 1575);
DISPLAY 0.680851 (4450 1575);
FORCEPROP 1 LAST MATERIAL IO
J 0
(4450 1375);
DISPLAY 0.723404 (4450 1375);
PAINT GREEN (4450 1375);
FORCEPROP 2 LAST PART_TYPE SMLF
J 0
(4450 1625);
DISPLAY 0.680851 (4450 1625);
FORCEPROP 1 LAST NEEDS_NO_SIZE TRUE
J 0
(4500 1250);
DISPLAY 0.723404 (4500 1250);
PAINT GREEN (4500 1250);
DISPLAY INVISIBLE (4500 1250);
FORCEPROP 1 LAST CDS_LMAN_SYM_OUTLINE -50,100,50,-100
J 0
(4500 1250);
DISPLAY 0.468085 (4500 1250);
PAINT GREEN (4500 1250);
DISPLAY INVISIBLE (4500 1250);
FORCEPROP 1 LAST PATH I169
J 0
(4500 1250);
DISPLAY 0.723404 (4500 1250);
PAINT GREEN (4500 1250);
DISPLAY INVISIBLE (4500 1250);
FORCEPROP 2 LAST CDS_LIB pure_quanta
J 0
(4500 1250);
DISPLAY INVISIBLE (4500 1250);
FORCEPROP 1 LAST LOCATION J1
J 0
(4450 1525);
DISPLAY 0.723404 (4450 1525);
PAINT GREEN (4450 1525);
FORCEPROP 0 LASTPIN (4300 1300) $PN 1
J 2
(4290 1310);
DISPLAY 0.680851 (4290 1310);
PAINT MONO (4290 1310);
FORCEPROP 0 LASTPIN (4300 1250) $PN 2
J 2
(4290 1260);
DISPLAY 0.680851 (4290 1260);
PAINT MONO (4290 1260);
FORCEPROP 0 LASTPIN (4300 1200) $PN 3
J 2
(4290 1210);
DISPLAY 0.680851 (4290 1210);
PAINT MONO (4290 1210);
FORCEPROP 0 LAST $SEC 1
J 0
(4450 1675);
DISPLAY 0.680851 (4450 1675);
PAINT MONO (4450 1675);
DISPLAY INVISIBLE (4450 1675);
FORCEPROP 0 LAST CDS_SEC 1
J 0
(4450 1675);
DISPLAY 0.680851 (4450 1675);
DISPLAY INVISIBLE (4450 1675);
FORCEADD Q_RES..2
(350 3900);
FORCEPROP 1 LAST WATTAGE 1/16W
J 2
(325 3850);
DISPLAY 0.510638 (325 3850);
PAINT SKYBLUE (325 3850);
FORCEPROP 1 LAST MATERIAL CHIP
J 2
(325 3800);
DISPLAY 0.510638 (325 3800);
PAINT SKYBLUE (325 3800);
FORCEPROP 1 LAST PACK_TYPE 0402LF
J 2
(325 3750);
DISPLAY 0.510638 (325 3750);
PAINT SKYBLUE (325 3750);
FORCEPROP 1 LAST TOLERANCE 1%
J 2
(325 3900);
DISPLAY 0.510638 (325 3900);
PAINT SKYBLUE (325 3900);
FORCEPROP 1 LAST VALUE 4.7K
J 2
(325 3950);
DISPLAY 0.510638 (325 3950);
PAINT SKYBLUE (325 3950);
FORCEPROP 1 LAST PART_NUMBER CS24702FB06
J 0
(390 3775);
DISPLAY 0.510638 (390 3775);
PAINT WHITE (390 3775);
DISPLAY INVISIBLE (390 3775);
FORCEPROP 1 LAST PATH I170
J 0
(400 4075);
DISPLAY 0.978723 (400 4075);
PAINT WHITE (400 4075);
DISPLAY INVISIBLE (400 4075);
FORCEPROP 2 LAST CDS_LIB pure_quanta
J 0
(350 3900);
DISPLAY INVISIBLE (350 3900);
FORCEPROP 1 LAST LOCATION R181
J 2
(325 4000);
DISPLAY 0.702128 (325 4000);
PAINT YELLOW (325 4000);
FORCEPROP 1 LASTPIN (350 4000) $PN 1
J 0
(355 3962);
DISPLAY 0.787234 (355 3962);
PAINT MONO (355 3962);
FORCEPROP 1 LASTPIN (350 3800) $PN 2
J 0
(355 3810);
DISPLAY 0.787234 (355 3810);
PAINT MONO (355 3810);
FORCEPROP 0 LAST $SEC 1
J 0
(325 4050);
DISPLAY 0.680851 (325 4050);
PAINT MONO (325 4050);
DISPLAY INVISIBLE (325 4050);
FORCEPROP 0 LAST CDS_SEC 1
J 0
(325 4050);
DISPLAY 0.680851 (325 4050);
DISPLAY INVISIBLE (325 4050);
FORCEADD Q_RES..2
(3900 1525);
FORCEPROP 1 LAST PACK_TYPE 0402LF
J 2
(3875 1375);
DISPLAY 0.510638 (3875 1375);
PAINT SKYBLUE (3875 1375);
FORCEPROP 1 LAST MATERIAL CHIP
J 2
(3875 1425);
DISPLAY 0.510638 (3875 1425);
PAINT SKYBLUE (3875 1425);
FORCEPROP 1 LAST WATTAGE 1/16W
J 2
(3875 1475);
DISPLAY 0.510638 (3875 1475);
PAINT SKYBLUE (3875 1475);
FORCEPROP 1 LAST VALUE 4.7K
J 2
(3875 1575);
DISPLAY 0.510638 (3875 1575);
PAINT SKYBLUE (3875 1575);
FORCEPROP 1 LAST TOLERANCE 1%
J 2
(3875 1525);
DISPLAY 0.510638 (3875 1525);
PAINT SKYBLUE (3875 1525);
FORCEPROP 1 LAST PART_NUMBER CS24702FB06
J 0
(3940 1400);
DISPLAY 0.510638 (3940 1400);
PAINT WHITE (3940 1400);
DISPLAY INVISIBLE (3940 1400);
FORCEPROP 1 LAST PATH I171
J 0
(3950 1700);
DISPLAY 0.978723 (3950 1700);
PAINT WHITE (3950 1700);
DISPLAY INVISIBLE (3950 1700);
FORCEPROP 2 LAST CDS_LIB pure_quanta
J 0
(3900 1525);
DISPLAY INVISIBLE (3900 1525);
FORCEPROP 1 LAST LOCATION R592
J 2
(3875 1625);
DISPLAY 0.702128 (3875 1625);
PAINT YELLOW (3875 1625);
FORCEPROP 1 LASTPIN (3900 1625) $PN 1
J 0
(3905 1587);
DISPLAY 0.787234 (3905 1587);
PAINT MONO (3905 1587);
FORCEPROP 1 LASTPIN (3900 1425) $PN 2
J 0
(3905 1435);
DISPLAY 0.787234 (3905 1435);
PAINT MONO (3905 1435);
FORCEPROP 0 LAST $SEC 1
J 0
(3875 1675);
DISPLAY 0.680851 (3875 1675);
PAINT MONO (3875 1675);
DISPLAY INVISIBLE (3875 1675);
FORCEPROP 0 LAST CDS_SEC 1
J 0
(3875 1675);
DISPLAY 0.680851 (3875 1675);
DISPLAY INVISIBLE (3875 1675);
FORCEADD Q_RES..1
(2275 3300);
FORCEPROP 1 LAST VALUE 33.2
J 2
(2475 3300);
DISPLAY 0.510638 (2475 3300);
PAINT SKYBLUE (2475 3300);
FORCEPROP 1 LAST MATERIAL CHIP
J 0
(2375 3275);
DISPLAY 0.510638 (2375 3275);
PAINT SKYBLUE (2375 3275);
FORCEPROP 2 LAST CDS_LIB pure_quanta
J 0
(2275 3300);
DISPLAY INVISIBLE (2275 3300);
FORCEPROP 1 LAST PATH I172
J 0
(2225 3450);
DISPLAY 0.978723 (2225 3450);
PAINT WHITE (2225 3450);
DISPLAY INVISIBLE (2225 3450);
FORCEPROP 1 LAST TOLERANCE 1%
J 0
(2275 3200);
DISPLAY 0.510638 (2275 3200);
PAINT SKYBLUE (2275 3200);
DISPLAY INVISIBLE (2275 3200);
FORCEPROP 1 LAST PART_NUMBER CS03322FB03
J 0
(2225 3400);
DISPLAY 0.510638 (2225 3400);
PAINT WHITE (2225 3400);
DISPLAY INVISIBLE (2225 3400);
FORCEPROP 1 LAST PACK_TYPE 0402LF
J 0
(2525 3150);
DISPLAY 0.510638 (2525 3150);
PAINT SKYBLUE (2525 3150);
DISPLAY INVISIBLE (2525 3150);
FORCEPROP 1 LAST WATTAGE 1/16W
J 2
(2250 3150);
DISPLAY 0.510638 (2250 3150);
PAINT SKYBLUE (2250 3150);
DISPLAY INVISIBLE (2250 3150);
FORCEPROP 1 LAST LOCATION R548
J 0
(2220 3330);
DISPLAY 0.702128 (2220 3330);
PAINT YELLOW (2220 3330);
FORCEPROP 1 LASTPIN (2175 3300) $PN 1
J 0
(2187 3312);
DISPLAY 0.787234 (2187 3312);
PAINT MONO (2187 3312);
FORCEPROP 1 LASTPIN (2375 3300) $PN 2
J 0
(2337 3312);
DISPLAY 0.787234 (2337 3312);
PAINT MONO (2337 3312);
FORCEPROP 0 LAST $SEC 1
J 0
(2225 3375);
DISPLAY 0.680851 (2225 3375);
PAINT MONO (2225 3375);
DISPLAY INVISIBLE (2225 3375);
FORCEPROP 0 LAST CDS_SEC 1
J 0
(2225 3375);
DISPLAY 0.680851 (2225 3375);
DISPLAY INVISIBLE (2225 3375);
FORCEADD Q_RES..1
(2900 2600);
FORCEPROP 1 LAST MATERIAL CHIP
J 0
(2950 2575);
DISPLAY 0.510638 (2950 2575);
PAINT SKYBLUE (2950 2575);
FORCEPROP 1 LAST VALUE 33.2
J 2
(3050 2600);
DISPLAY 0.510638 (3050 2600);
PAINT SKYBLUE (3050 2600);
FORCEPROP 2 LAST CDS_LIB pure_quanta
J 0
(2900 2600);
DISPLAY INVISIBLE (2900 2600);
FORCEPROP 1 LAST PATH I173
J 0
(2850 2750);
DISPLAY 0.978723 (2850 2750);
PAINT WHITE (2850 2750);
DISPLAY INVISIBLE (2850 2750);
FORCEPROP 1 LAST WATTAGE 1/16W
J 2
(2875 2450);
DISPLAY 0.510638 (2875 2450);
PAINT SKYBLUE (2875 2450);
DISPLAY INVISIBLE (2875 2450);
FORCEPROP 1 LAST PACK_TYPE 0402LF
J 0
(3150 2450);
DISPLAY 0.510638 (3150 2450);
PAINT SKYBLUE (3150 2450);
DISPLAY INVISIBLE (3150 2450);
FORCEPROP 1 LAST PART_NUMBER CS03322FB03
J 0
(2850 2700);
DISPLAY 0.510638 (2850 2700);
PAINT WHITE (2850 2700);
DISPLAY INVISIBLE (2850 2700);
FORCEPROP 1 LAST TOLERANCE 1%
J 0
(2900 2500);
DISPLAY 0.510638 (2900 2500);
PAINT SKYBLUE (2900 2500);
DISPLAY INVISIBLE (2900 2500);
FORCEPROP 1 LAST LOCATION R551
J 0
(2750 2600);
DISPLAY 0.702128 (2750 2600);
PAINT YELLOW (2750 2600);
FORCEPROP 1 LASTPIN (2800 2600) $PN 1
J 0
(2812 2612);
DISPLAY 0.787234 (2812 2612);
PAINT MONO (2812 2612);
FORCEPROP 1 LASTPIN (3000 2600) $PN 2
J 0
(2962 2612);
DISPLAY 0.787234 (2962 2612);
PAINT MONO (2962 2612);
FORCEPROP 0 LAST $SEC 1
J 0
(2750 2650);
DISPLAY 0.680851 (2750 2650);
PAINT MONO (2750 2650);
DISPLAY INVISIBLE (2750 2650);
FORCEPROP 0 LAST CDS_SEC 1
J 0
(2750 2650);
DISPLAY 0.680851 (2750 2650);
DISPLAY INVISIBLE (2750 2650);
FORCEADD Q_RES..1
(4200 3550);
FORCEPROP 1 LAST MATERIAL CHIP
J 0
(4300 3525);
DISPLAY 0.510638 (4300 3525);
PAINT SKYBLUE (4300 3525);
FORCEPROP 1 LAST VALUE 33.2
J 2
(4400 3550);
DISPLAY 0.510638 (4400 3550);
PAINT SKYBLUE (4400 3550);
FORCEPROP 1 LAST WATTAGE 1/16W
J 2
(4175 3400);
DISPLAY 0.510638 (4175 3400);
PAINT SKYBLUE (4175 3400);
DISPLAY INVISIBLE (4175 3400);
FORCEPROP 1 LAST PACK_TYPE 0402LF
J 0
(4450 3400);
DISPLAY 0.510638 (4450 3400);
PAINT SKYBLUE (4450 3400);
DISPLAY INVISIBLE (4450 3400);
FORCEPROP 1 LAST PART_NUMBER CS03322FB03
J 0
(4150 3650);
DISPLAY 0.510638 (4150 3650);
PAINT WHITE (4150 3650);
DISPLAY INVISIBLE (4150 3650);
FORCEPROP 1 LAST TOLERANCE 1%
J 0
(4200 3450);
DISPLAY 0.510638 (4200 3450);
PAINT SKYBLUE (4200 3450);
DISPLAY INVISIBLE (4200 3450);
FORCEPROP 1 LAST PATH I174
J 0
(4150 3700);
DISPLAY 0.978723 (4150 3700);
PAINT WHITE (4150 3700);
DISPLAY INVISIBLE (4150 3700);
FORCEPROP 2 LAST CDS_LIB pure_quanta
J 0
(4200 3550);
DISPLAY INVISIBLE (4200 3550);
FORCEPROP 1 LAST LOCATION R555
J 0
(4050 3550);
DISPLAY 0.702128 (4050 3550);
PAINT YELLOW (4050 3550);
FORCEPROP 1 LASTPIN (4100 3550) $PN 1
J 0
(4112 3562);
DISPLAY 0.787234 (4112 3562);
PAINT MONO (4112 3562);
FORCEPROP 1 LASTPIN (4300 3550) $PN 2
J 0
(4262 3562);
DISPLAY 0.787234 (4262 3562);
PAINT MONO (4262 3562);
FORCEPROP 0 LAST $SEC 1
J 0
(4050 3600);
DISPLAY 0.680851 (4050 3600);
PAINT MONO (4050 3600);
DISPLAY INVISIBLE (4050 3600);
FORCEPROP 0 LAST CDS_SEC 1
J 0
(4050 3600);
DISPLAY 0.680851 (4050 3600);
DISPLAY INVISIBLE (4050 3600);
FORCEADD Q_RES..1
(3425 1900);
FORCEPROP 1 LAST VALUE 33.2
J 2
(3625 1900);
DISPLAY 0.510638 (3625 1900);
PAINT SKYBLUE (3625 1900);
FORCEPROP 1 LAST MATERIAL CHIP
J 0
(3525 1875);
DISPLAY 0.510638 (3525 1875);
PAINT SKYBLUE (3525 1875);
FORCEPROP 1 LAST WATTAGE 1/16W
J 2
(3400 1750);
DISPLAY 0.510638 (3400 1750);
PAINT SKYBLUE (3400 1750);
DISPLAY INVISIBLE (3400 1750);
FORCEPROP 1 LAST PACK_TYPE 0402LF
J 0
(3675 1750);
DISPLAY 0.510638 (3675 1750);
PAINT SKYBLUE (3675 1750);
DISPLAY INVISIBLE (3675 1750);
FORCEPROP 1 LAST PART_NUMBER CS03322FB03
J 0
(3375 2000);
DISPLAY 0.510638 (3375 2000);
PAINT WHITE (3375 2000);
DISPLAY INVISIBLE (3375 2000);
FORCEPROP 1 LAST TOLERANCE 1%
J 0
(3425 1800);
DISPLAY 0.510638 (3425 1800);
PAINT SKYBLUE (3425 1800);
DISPLAY INVISIBLE (3425 1800);
FORCEPROP 1 LAST PATH I175
J 0
(3375 2050);
DISPLAY 0.978723 (3375 2050);
PAINT WHITE (3375 2050);
DISPLAY INVISIBLE (3375 2050);
FORCEPROP 2 LAST CDS_LIB pure_quanta
J 0
(3425 1900);
DISPLAY INVISIBLE (3425 1900);
FORCEPROP 1 LAST LOCATION R556
J 0
(3275 1900);
DISPLAY 0.702128 (3275 1900);
PAINT YELLOW (3275 1900);
FORCEPROP 1 LASTPIN (3325 1900) $PN 1
J 0
(3337 1912);
DISPLAY 0.787234 (3337 1912);
PAINT MONO (3337 1912);
FORCEPROP 1 LASTPIN (3525 1900) $PN 2
J 0
(3487 1912);
DISPLAY 0.787234 (3487 1912);
PAINT MONO (3487 1912);
FORCEPROP 0 LAST $SEC 1
J 0
(3275 1950);
DISPLAY 0.680851 (3275 1950);
PAINT MONO (3275 1950);
DISPLAY INVISIBLE (3275 1950);
FORCEPROP 0 LAST CDS_SEC 1
J 0
(3275 1950);
DISPLAY 0.680851 (3275 1950);
DISPLAY INVISIBLE (3275 1950);
FORCEADD Q_RES..1
(3425 1825);
FORCEPROP 1 LAST MATERIAL CHIP
J 0
(3525 1800);
DISPLAY 0.510638 (3525 1800);
PAINT SKYBLUE (3525 1800);
FORCEPROP 1 LAST VALUE 33.2
J 2
(3625 1825);
DISPLAY 0.510638 (3625 1825);
PAINT SKYBLUE (3625 1825);
FORCEPROP 1 LAST WATTAGE 1/16W
J 2
(3400 1675);
DISPLAY 0.510638 (3400 1675);
PAINT SKYBLUE (3400 1675);
DISPLAY INVISIBLE (3400 1675);
FORCEPROP 1 LAST PACK_TYPE 0402LF
J 0
(3675 1675);
DISPLAY 0.510638 (3675 1675);
PAINT SKYBLUE (3675 1675);
DISPLAY INVISIBLE (3675 1675);
FORCEPROP 1 LAST PART_NUMBER CS03322FB03
J 0
(3375 1925);
DISPLAY 0.510638 (3375 1925);
PAINT WHITE (3375 1925);
DISPLAY INVISIBLE (3375 1925);
FORCEPROP 1 LAST TOLERANCE 1%
J 0
(3425 1725);
DISPLAY 0.510638 (3425 1725);
PAINT SKYBLUE (3425 1725);
DISPLAY INVISIBLE (3425 1725);
FORCEPROP 1 LAST PATH I176
J 0
(3375 1975);
DISPLAY 0.978723 (3375 1975);
PAINT WHITE (3375 1975);
DISPLAY INVISIBLE (3375 1975);
FORCEPROP 2 LAST CDS_LIB pure_quanta
J 0
(3425 1825);
DISPLAY INVISIBLE (3425 1825);
FORCEPROP 1 LAST LOCATION R559
J 0
(3275 1825);
DISPLAY 0.702128 (3275 1825);
PAINT YELLOW (3275 1825);
FORCEPROP 1 LASTPIN (3325 1825) $PN 1
J 0
(3337 1837);
DISPLAY 0.787234 (3337 1837);
PAINT MONO (3337 1837);
FORCEPROP 1 LASTPIN (3525 1825) $PN 2
J 0
(3487 1837);
DISPLAY 0.787234 (3487 1837);
PAINT MONO (3487 1837);
FORCEPROP 0 LAST $SEC 1
J 0
(3275 1875);
DISPLAY 0.680851 (3275 1875);
PAINT MONO (3275 1875);
DISPLAY INVISIBLE (3275 1875);
FORCEPROP 0 LAST CDS_SEC 1
J 0
(3275 1875);
DISPLAY 0.680851 (3275 1875);
DISPLAY INVISIBLE (3275 1875);
FORCEADD UNIVERSAL_POWER..1
(2875 -425);
FORCEPROP 3 LASTPIN (2875 -475) SIG_NAME P3V3_AUX\g
J 0
(2885 -465);
DISPLAY 0.659574 (2885 -465);
PAINT MONO (2885 -465);
DISPLAY INVISIBLE (2885 -465);
FORCEPROP 1 LAST HDL_POWER P3V3_AUX
J 1
(2875 -375);
DISPLAY 0.702128 (2875 -375);
PAINT GREEN (2875 -375);
FORCEPROP 2 LAST CDS_LIB logical_power
J 0
(2875 -425);
DISPLAY INVISIBLE (2875 -425);
FORCEPROP 1 LAST PATH I2
J 0
(2925 -400);
DISPLAY 0.872340 (2925 -400);
PAINT AQUA (2925 -400);
DISPLAY INVISIBLE (2925 -400);
FORCEADD Q_RES..2
R 2
(2875 -675);
FORCEPROP 1 LAST VALUE 4.7K
J 0
(2925 -600);
DISPLAY 0.510638 (2925 -600);
PAINT SKYBLUE (2925 -600);
FORCEPROP 1 LAST TOLERANCE 1%
J 0
(2925 -650);
DISPLAY 0.510638 (2925 -650);
PAINT SKYBLUE (2925 -650);
FORCEPROP 1 LAST MATERIAL CHIP
J 0
(2925 -700);
DISPLAY 0.510638 (2925 -700);
PAINT SKYBLUE (2925 -700);
FORCEPROP 1 LAST PART_NUMBER CS24702FB06
J 0
(2925 -750);
DISPLAY 0.510638 (2925 -750);
PAINT WHITE (2925 -750);
FORCEPROP 1 LAST PACK_TYPE 0402LF
J 0
(2925 -800);
DISPLAY 0.510638 (2925 -800);
PAINT SKYBLUE (2925 -800);
FORCEPROP 2 LAST CDS_LIB pure_quanta
J 0
(2875 -675);
DISPLAY INVISIBLE (2875 -675);
FORCEPROP 1 LAST PATH I3
J 2
(2825 -500);
DISPLAY 0.978723 (2825 -500);
PAINT WHITE (2825 -500);
DISPLAY INVISIBLE (2825 -500);
FORCEPROP 1 LAST WATTAGE 1/16W
J 2
(2835 -700);
DISPLAY 0.510638 (2835 -700);
PAINT SKYBLUE (2835 -700);
DISPLAY INVISIBLE (2835 -700);
FORCEPROP 1 LAST LOCATION R563
J 0
(2925 -550);
DISPLAY 0.702128 (2925 -550);
PAINT YELLOW (2925 -550);
FORCEPROP 1 LASTPIN (2875 -575) $PN 1
J 2
(2870 -613);
DISPLAY 0.808511 (2870 -613);
PAINT WHITE (2870 -613);
FORCEPROP 1 LASTPIN (2875 -775) $PN 2
J 2
(2870 -765);
DISPLAY 0.808511 (2870 -765);
PAINT WHITE (2870 -765);
FORCEPROP 0 LAST $SEC 1
J 0
(2850 -500);
DISPLAY 0.680851 (2850 -500);
PAINT MONO (2850 -500);
DISPLAY INVISIBLE (2850 -500);
FORCEPROP 0 LAST CDS_SEC 1
J 0
(2850 -500);
DISPLAY 0.680851 (2850 -500);
DISPLAY INVISIBLE (2850 -500);
FORCEADD SN74LVC1G07DCKR..1
(450 -950);
FORCEPROP 2 LAST VALUE SN74LVC1G07DCKR
J 0
(350 -625);
DISPLAY 0.680851 (350 -625);
FORCEPROP 1 LAST PART_NUMBER AL1G0007016
J 0
(331 -730);
DISPLAY 0.723404 (331 -730);
PAINT GREEN (331 -730);
FORCEPROP 1 LAST MATERIAL IC
J 0
(331 -790);
DISPLAY 0.723404 (331 -790);
PAINT GREEN (331 -790);
FORCEPROP 2 LAST PART_TYPE SMLF
J 0
(350 -575);
DISPLAY 0.680851 (350 -575);
FORCEPROP 1 LAST PATH I61
J 0
(450 -950);
DISPLAY 0.723404 (450 -950);
PAINT GREEN (450 -950);
DISPLAY INVISIBLE (450 -950);
FORCEPROP 2 LAST CDS_LIB pure_quanta
J 0
(450 -950);
DISPLAY INVISIBLE (450 -950);
FORCEPROP 1 LAST CDS_LMAN_SYM_OUTLINE -125,150,125,-150
J 0
(450 -950);
DISPLAY 0.468085 (450 -950);
PAINT GREEN (450 -950);
DISPLAY INVISIBLE (450 -950);
FORCEPROP 1 LAST NEEDS_NO_SIZE TRUE
J 0
(450 -950);
DISPLAY 0.723404 (450 -950);
PAINT GREEN (450 -950);
DISPLAY INVISIBLE (450 -950);
FORCEPROP 1 LAST LOCATION U44
J 0
(331 -667);
DISPLAY 0.723404 (331 -667);
PAINT GREEN (331 -667);
FORCEPROP 0 LASTPIN (175 -950) $PN 2
J 2
(165 -940);
DISPLAY 0.680851 (165 -940);
PAINT MONO (165 -940);
FORCEPROP 0 LASTPIN (175 -1050) $PN 3
J 2
(165 -1040);
DISPLAY 0.680851 (165 -1040);
PAINT MONO (165 -1040);
FORCEPROP 0 LASTPIN (725 -1050) $PN 1
J 0
(735 -1040);
DISPLAY 0.680851 (735 -1040);
PAINT MONO (735 -1040);
FORCEPROP 0 LASTPIN (175 -850) $PN 5
J 2
(165 -840);
DISPLAY 0.680851 (165 -840);
PAINT MONO (165 -840);
FORCEPROP 0 LASTPIN (725 -950) $PN 4
J 0
(735 -940);
DISPLAY 0.680851 (735 -940);
PAINT MONO (735 -940);
FORCEPROP 0 LAST $SEC 1
J 0
(350 -525);
DISPLAY 0.680851 (350 -525);
PAINT MONO (350 -525);
DISPLAY INVISIBLE (350 -525);
FORCEPROP 0 LAST CDS_SEC 1
J 0
(350 -525);
DISPLAY 0.680851 (350 -525);
DISPLAY INVISIBLE (350 -525);
FORCEADD UNIVERSAL_GND..1
(125 -1250);
FORCEPROP 3 LASTPIN (125 -1200) SIG_NAME GND\g
J 0
(135 -1190);
DISPLAY 0.659574 (135 -1190);
PAINT MONO (135 -1190);
DISPLAY INVISIBLE (135 -1190);
FORCEPROP 2 LAST CDS_LIB logical_power
J 0
(125 -1250);
DISPLAY INVISIBLE (125 -1250);
FORCEPROP 1 LAST HDL_POWER GND
J 1
(150 -1325);
DISPLAY 0.702128 (150 -1325);
PAINT GREEN (150 -1325);
DISPLAY INVISIBLE (150 -1325);
FORCEPROP 1 LAST PATH I62
J 0
(200 -1250);
DISPLAY 0.872340 (200 -1250);
PAINT AQUA (200 -1250);
DISPLAY INVISIBLE (200 -1250);
FORCEADD UNIVERSAL_GND..1
(-25 -650);
FORCEPROP 3 LASTPIN (-25 -600) SIG_NAME GND\g
J 0
(-15 -590);
DISPLAY 0.659574 (-15 -590);
PAINT MONO (-15 -590);
DISPLAY INVISIBLE (-15 -590);
FORCEPROP 2 LAST CDS_LIB logical_power
J 0
(-25 -650);
DISPLAY INVISIBLE (-25 -650);
FORCEPROP 1 LAST HDL_POWER GND
J 1
(0 -725);
DISPLAY 0.702128 (0 -725);
PAINT GREEN (0 -725);
DISPLAY INVISIBLE (0 -725);
FORCEPROP 1 LAST PATH I64
J 0
(50 -650);
DISPLAY 0.872340 (50 -650);
PAINT AQUA (50 -650);
DISPLAY INVISIBLE (50 -650);
FORCEADD Q_CAP..1
(-25 -450);
FORCEPROP 1 LAST VALUE 0.1UF
J 0
(25 -400);
DISPLAY 0.510638 (25 -400);
PAINT SKYBLUE (25 -400);
FORCEPROP 1 LAST MATERIAL X7R
J 0
(25 -550);
DISPLAY 0.510638 (25 -550);
PAINT SKYBLUE (25 -550);
FORCEPROP 1 LAST PACK_TYPE 0402
J 0
(25 -650);
DISPLAY 0.510638 (25 -650);
PAINT SKYBLUE (25 -650);
FORCEPROP 1 LAST TOLERANCE 10%
J 0
(25 -500);
DISPLAY 0.510638 (25 -500);
PAINT SKYBLUE (25 -500);
FORCEPROP 1 LAST VOLTAGE 25V
J 0
(25 -450);
DISPLAY 0.510638 (25 -450);
PAINT SKYBLUE (25 -450);
FORCEPROP 1 LAST PART_NUMBER CH4104K1B00
J 0
(25 -600);
DISPLAY 0.510638 (25 -600);
PAINT WHITE (25 -600);
FORCEPROP 1 LAST PATH I65
J 0
(25 -300);
DISPLAY 0.978723 (25 -300);
PAINT WHITE (25 -300);
DISPLAY INVISIBLE (25 -300);
FORCEPROP 2 LAST SEC_TYPE 0402
J 0
(25 -250);
DISPLAY 1.021277 (25 -250);
DISPLAY INVISIBLE (25 -250);
FORCEPROP 2 LAST CDS_LIB pure_quanta
J 0
(-25 -450);
DISPLAY INVISIBLE (-25 -450);
FORCEPROP 1 LAST LOCATION C304
J 0
(25 -350);
DISPLAY 0.702128 (25 -350);
PAINT YELLOW (25 -350);
FORCEPROP 1 LASTPIN (-25 -350) $PN 1
J 0
(-15 -370);
DISPLAY 0.808511 (-15 -370);
PAINT WHITE (-15 -370);
FORCEPROP 1 LASTPIN (-25 -550) $PN 2
J 0
(-15 -570);
DISPLAY 0.808511 (-15 -570);
PAINT WHITE (-15 -570);
FORCEPROP 2 LAST SEC 1
J 0
(25 -250);
DISPLAY 0.680851 (25 -250);
PAINT MONO (25 -250);
DISPLAY INVISIBLE (25 -250);
FORCEADD Q_RES..1
(-925 -950);
FORCEPROP 1 LAST MATERIAL CHIP
J 0
(-750 -975);
DISPLAY 0.510638 (-750 -975);
PAINT SKYBLUE (-750 -975);
FORCEPROP 1 LAST VALUE 33.2
J 2
(-775 -975);
DISPLAY 0.510638 (-775 -975);
PAINT SKYBLUE (-775 -975);
FORCEPROP 1 LAST TOLERANCE 1%
J 0
(-925 -1050);
DISPLAY 0.510638 (-925 -1050);
PAINT SKYBLUE (-925 -1050);
DISPLAY INVISIBLE (-925 -1050);
FORCEPROP 1 LAST PART_NUMBER CS03322FB03
J 0
(-975 -850);
DISPLAY 0.510638 (-975 -850);
PAINT WHITE (-975 -850);
DISPLAY INVISIBLE (-975 -850);
FORCEPROP 1 LAST PACK_TYPE 0402LF
J 0
(-675 -1100);
DISPLAY 0.510638 (-675 -1100);
PAINT SKYBLUE (-675 -1100);
DISPLAY INVISIBLE (-675 -1100);
FORCEPROP 1 LAST WATTAGE 1/16W
J 2
(-950 -1100);
DISPLAY 0.510638 (-950 -1100);
PAINT SKYBLUE (-950 -1100);
DISPLAY INVISIBLE (-950 -1100);
FORCEPROP 1 LAST PATH I67
J 0
(-975 -800);
DISPLAY 0.978723 (-975 -800);
PAINT WHITE (-975 -800);
DISPLAY INVISIBLE (-975 -800);
FORCEPROP 2 LAST CDS_LIB pure_quanta
J 0
(-925 -950);
DISPLAY INVISIBLE (-925 -950);
FORCEPROP 1 LAST LOCATION R752
J 0
(-975 -900);
DISPLAY 0.702128 (-975 -900);
PAINT YELLOW (-975 -900);
FORCEPROP 1 LASTPIN (-1025 -950) $PN 1
J 0
(-1013 -938);
DISPLAY 0.808511 (-1013 -938);
PAINT WHITE (-1013 -938);
FORCEPROP 1 LASTPIN (-825 -950) $PN 2
J 0
(-863 -938);
DISPLAY 0.808511 (-863 -938);
PAINT WHITE (-863 -938);
FORCEPROP 0 LAST $SEC 1
J 0
(-975 -850);
DISPLAY 0.680851 (-975 -850);
PAINT MONO (-975 -850);
DISPLAY INVISIBLE (-975 -850);
FORCEPROP 0 LAST CDS_SEC 1
J 0
(-975 -850);
DISPLAY 0.680851 (-975 -850);
DISPLAY INVISIBLE (-975 -850);
FORCEADD OFFPAGE..1
(-1850 -950);
FORCEPROP 2 LAST $XR0 15 
J 0
(-2101 -950);
DISPLAY 0.638298 (-2101 -950);
PAINT MONO (-2101 -950);
FORCEPROP 2 LAST CDS_LIB standard
J 0
(-1850 -950);
DISPLAY INVISIBLE (-1850 -950);
FORCEPROP 1 LAST OFFPAGE TRUE
J 0
(-1525 -1075);
DISPLAY 0.872340 (-1525 -1075);
PAINT GREEN (-1525 -1075);
DISPLAY INVISIBLE (-1525 -1075);
FORCEPROP 1 LAST COMMENT_BODY TRUE
J 0
(-1725 -1050);
DISPLAY 0.872340 (-1725 -1050);
PAINT PEACH (-1725 -1050);
DISPLAY INVISIBLE (-1725 -1050);
FORCEPROP 2 LAST PATH I70
J 0
(-2050 -900);
DISPLAY 0.680851 (-2050 -900);
DISPLAY INVISIBLE (-2050 -900);
FORCEADD OFFPAGE..2
(3325 -950);
FORCEPROP 2 LAST $XR0 21 
J 0
(3514 -950);
DISPLAY 0.638298 (3514 -950);
PAINT MONO (3514 -950);
FORCEPROP 1 LAST COMMENT_BODY TRUE
J 0
(3280 -1045);
DISPLAY 0.872340 (3280 -1045);
PAINT GREEN (3280 -1045);
DISPLAY INVISIBLE (3280 -1045);
FORCEPROP 1 LAST OFFPAGE TRUE
J 0
(3650 -1075);
DISPLAY 0.872340 (3650 -1075);
DISPLAY INVISIBLE (3650 -1075);
FORCEPROP 2 LAST PATH I71
J 0
(3625 -900);
DISPLAY 0.680851 (3625 -900);
DISPLAY INVISIBLE (3625 -900);
FORCEPROP 2 LAST CDS_LIB standard
J 0
(3325 -950);
DISPLAY INVISIBLE (3325 -950);
FORCEADD UNIVERSAL_POWER..1
(-200 -175);
FORCEPROP 3 LASTPIN (-200 -225) SIG_NAME P3V3_AUX\g
J 0
(-190 -215);
DISPLAY 0.659574 (-190 -215);
PAINT MONO (-190 -215);
DISPLAY INVISIBLE (-190 -215);
FORCEPROP 1 LAST HDL_POWER P3V3_AUX
J 1
(-200 -125);
DISPLAY 0.702128 (-200 -125);
PAINT GREEN (-200 -125);
FORCEPROP 2 LAST CDS_LIB logical_power
J 0
(-200 -175);
DISPLAY INVISIBLE (-200 -175);
FORCEPROP 1 LAST PATH I72
J 0
(-150 -150);
DISPLAY 0.872340 (-150 -150);
PAINT AQUA (-150 -150);
DISPLAY INVISIBLE (-150 -150);
FORCEADD Q_RES..1
(1825 -950);
FORCEPROP 1 LAST MATERIAL CHIP
J 0
(2000 -975);
DISPLAY 0.510638 (2000 -975);
PAINT SKYBLUE (2000 -975);
FORCEPROP 1 LAST VALUE 33.2
J 2
(1975 -975);
DISPLAY 0.510638 (1975 -975);
PAINT SKYBLUE (1975 -975);
FORCEPROP 1 LAST TOLERANCE 1%
J 0
(1825 -1050);
DISPLAY 0.510638 (1825 -1050);
PAINT SKYBLUE (1825 -1050);
DISPLAY INVISIBLE (1825 -1050);
FORCEPROP 1 LAST PART_NUMBER CS03322FB03
J 0
(1775 -850);
DISPLAY 0.510638 (1775 -850);
PAINT WHITE (1775 -850);
DISPLAY INVISIBLE (1775 -850);
FORCEPROP 1 LAST PACK_TYPE 0402LF
J 0
(2075 -1100);
DISPLAY 0.510638 (2075 -1100);
PAINT SKYBLUE (2075 -1100);
DISPLAY INVISIBLE (2075 -1100);
FORCEPROP 1 LAST WATTAGE 1/16W
J 2
(1800 -1100);
DISPLAY 0.510638 (1800 -1100);
PAINT SKYBLUE (1800 -1100);
DISPLAY INVISIBLE (1800 -1100);
FORCEPROP 1 LAST PATH I73
J 0
(1775 -800);
DISPLAY 0.978723 (1775 -800);
PAINT WHITE (1775 -800);
DISPLAY INVISIBLE (1775 -800);
FORCEPROP 2 LAST CDS_LIB pure_quanta
J 0
(1825 -950);
DISPLAY INVISIBLE (1825 -950);
FORCEPROP 1 LAST LOCATION R827
J 0
(1775 -900);
DISPLAY 0.702128 (1775 -900);
PAINT YELLOW (1775 -900);
FORCEPROP 1 LASTPIN (1725 -950) $PN 1
J 0
(1737 -938);
DISPLAY 0.808511 (1737 -938);
PAINT WHITE (1737 -938);
FORCEPROP 1 LASTPIN (1925 -950) $PN 2
J 0
(1887 -938);
DISPLAY 0.808511 (1887 -938);
PAINT WHITE (1887 -938);
FORCEPROP 0 LAST $SEC 1
J 0
(1775 -850);
DISPLAY 0.680851 (1775 -850);
PAINT MONO (1775 -850);
DISPLAY INVISIBLE (1775 -850);
FORCEPROP 0 LAST CDS_SEC 1
J 0
(1775 -850);
DISPLAY 0.680851 (1775 -850);
DISPLAY INVISIBLE (1775 -850);
FORCEADD QUANTA_TITLE_BLOCK_C..1
(5500 -1700);
FORCEPROP 0 LAST CDS_CON_LAST_MODIFIED Fri Aug 25 17:25:41 2023
J 0
(3615 -1685);
DISPLAY INVISIBLE (3615 -1685);
FORCEPROP 2 LAST Q_DEPT 
J 1
(1737 -1651);
DISPLAY 1.957447 (1737 -1651);
PAINT GREEN (1737 -1651);
FORCEPROP 1 LAST CUSTOM_TXT_CDS <CON_LAST_MODIFIED>
J 0
(3615 -1685);
DISPLAY 0.978723 (3615 -1685);
FORCEPROP 2 LAST CUSTOM_TXT_CDS <XR_PAGE_TITLE>
J 0
(-2390 3550);
DISPLAY 0.638298 (-2390 3550);
PAINT PINK (-2390 3550);
DISPLAY INVISIBLE (-2390 3550);
FORCEPROP 1 LAST CUSTOM_TXT_CDS <NAME_2>
J 0
(2325 -1650);
FORCEPROP 1 LAST CUSTOM_TXT_CDS <NAME_1>
J 0
(2325 -1525);
FORCEPROP 1 LAST CUSTOM_TXT_CDS <Q_NUMBER>
J 0
(4097 -1597);
DISPLAY 1.212766 (4097 -1597);
FORCEPROP 1 LAST CUSTOM_TXT_CDS <Q_PROJ>
J 0
(3118 -1598);
DISPLAY 1.212766 (3118 -1598);
FORCEPROP 1 LAST CUSTOM_TXT_CDS <Q_REV>
J 0
(5316 -1597);
DISPLAY 1.212766 (5316 -1597);
FORCEPROP 1 LAST CUSTOM_TXT_CDS <CON_PAGE_NUM> OF <CON_TOTAL_PAGES>
J 0
(5054 -1682);
DISPLAY 0.978723 (5054 -1682);
FORCEPROP 1 LAST Q_TITLE BMC ROM
J 0
(-3866 -1674);
DISPLAY 2.446809 (-3866 -1674);
PAINT GREEN (-3866 -1674);
FORCEPROP 2 LAST CDS_XR_PAGE_TITLE CR-25 : @SCM_LIB.SCM(SCH_1):PAGE25
J 0
(-2390 3550);
DISPLAY 0.638298 (-2390 3550);
PAINT PINK (-2390 3550);
DISPLAY INVISIBLE (-2390 3550);
FORCEPROP 1 LAST CDS_LMAN_SYM_OUTLINE -9475,6775,100,-125
J 0
(5500 -1700);
DISPLAY 0.468085 (5500 -1700);
PAINT GREEN (5500 -1700);
DISPLAY INVISIBLE (5500 -1700);
FORCEPROP 2 LAST CDS_LIB pure_quanta
J 0
(5500 -1700);
DISPLAY INVISIBLE (5500 -1700);
FORCEPROP 2 LAST PAGE_BORDER TRUE
J 0
(-2390 3550);
DISPLAY 0.638298 (-2390 3550);
PAINT PINK (-2390 3550);
DISPLAY INVISIBLE (-2390 3550);
FORCEPROP 1 LAST COMMENT_BODY TRUE
J 0
(5512 -1713);
DISPLAY 0.978723 (5512 -1713);
PAINT PEACH (5512 -1713);
DISPLAY INVISIBLE (5512 -1713);
FORCEADD DNS..2
(3125 2925);
PAINT RED (3125 2925);
FORCEPROP 2 LAST CDS_LIB mstr_misc
J 0
(3125 2925);
DISPLAY INVISIBLE (3125 2925);
FORCEPROP 1 LAST COMMENT_BODY TRUE
R 1
J 0
(3200 2700);
DISPLAY 0.872340 (3200 2700);
PAINT PEACH (3200 2700);
DISPLAY INVISIBLE (3200 2700);
WIRE 16 -1 (3900 1625)(3900 1675);
WIRE 16 -1 (2375 4100)(2375 4175);
WIRE 16 -1 (2375 4100)(2675 4100);
WIRE 16 -1 (3675 3100)(3675 3225);
WIRE 16 -1 (3675 3100)(3525 3100);
WIRE 16 -1 (2875 -475)(2875 -575);
WIRE 16 -1 (350 4000)(350 4050);
WIRE 16 -1 (-200 -225)(-200 -275);
WIRE 16 -1 (125 -1200)(125 -1050);
WIRE 16 -1 (-25 -600)(-25 -550);
WIRE 16 -1 (3675 2900)(3675 2875);
WIRE 16 -1 (3850 2500)(3850 2475);
WIRE 16 -1 (3850 2500)(4100 2500);
WIRE 16 -1 (2375 3900)(2375 3825);
WIRE 16 -1 (3450 3225)(3450 3250);
WIRE 16 -1 (1350 3500)(1350 3475);
WIRE 16 -1 (1350 3500)(1900 3500);
WIRE 16 -1 (1350 3600)(1350 3500);
WIRE 16 -1 (1900 3600)(1350 3600);
WIRE 16 -1 (2675 3750)(2725 3750);
WIRE 16 -1 (2675 4100)(2675 3750);
WIRE 16 -1 (3525 2700)(4100 2700);
WIRE 16 -1 (3100 3100)(3100 3025);
WIRE 16 -1 (3525 3100)(3525 2700);
WIRE 16 -1 (3525 3100)(3100 3100);
WIRE 16 -1 (3425 3250)(3450 3250);
WIRE 16 -1 (125 -1050)(175 -1050);
WIRE 16 -1 (-25 -275)(-25 -350);
WIRE 16 -1 (-200 -275)(-25 -275);
WIRE 16 -1 (-200 -275)(-200 -850);
WIRE 16 -1 (-200 -850)(175 -850);
WIRE 16 -1 (725 -950)(1725 -950);
FORCEPROP 2 LAST SIG_NAME RST_SPI_FLASH_BUF_R3_N
J 0
(815 -940);
DISPLAY 0.808511 (815 -940);
WIRE 16 -1 (3100 2825)(3100 2600);
WIRE 16 -1 (3100 2600)(4100 2600);
WIRE 16 -1 (3000 2600)(3100 2600);
FORCEPROP 2 LAST SIG_NAME FLASH_R_WP_STATUS
J 0
(3140 2610);
DISPLAY 0.851064 (3140 2610);
WIRE 16 -1 (2800 2600)(2025 2600);
FORCEPROP 2 LAST SIG_NAME FLASH_WP_STATUS
J 0
(2040 2610);
DISPLAY 0.851064 (2040 2610);
WIRE 16 -1 (175 -950)(-825 -950);
FORCEPROP 2 LAST SIG_NAME RST_SPI_FLASH_R_N
J 0
(-535 -940);
DISPLAY 0.808511 (-535 -940);
WIRE 16 -1 (2875 -775)(2875 -950);
WIRE 16 -1 (2875 -950)(3275 -950);
WIRE 16 -1 (1925 -950)(2875 -950);
FORCEPROP 2 LAST SIG_NAME RST_SPI_FLASH_BUF_N
J 0
(2065 -940);
DISPLAY 0.808511 (2065 -940);
WIRE 16 -1 (3325 1900)(2125 1900);
FORCEPROP 2 LAST SIG_NAME SPI_BMC_BT_WP1_N_R
J 0
(2315 1910);
DISPLAY 0.851064 (2315 1910);
WIRE 16 -1 (3325 1825)(2125 1825);
FORCEPROP 2 LAST SIG_NAME SPI_BMC_BT_WP0_N_R
J 0
(2315 1835);
DISPLAY 0.851064 (2315 1835);
WIRE 16 -1 (3675 1825)(3525 1825);
WIRE 16 -1 (3725 1250)(4300 1250);
WIRE 16 -1 (3675 1900)(3525 1900);
WIRE 16 -1 (3675 1900)(3675 1825);
WIRE 16 -1 (3675 1900)(3725 1900);
WIRE 16 -1 (3725 1250)(3725 1900);
WIRE 16 -1 (5000 1900)(3725 1900);
WIRE 16 -1 (5000 2600)(5000 1900);
WIRE 16 -1 (5000 3050)(5000 2600);
WIRE 16 -1 (4450 2600)(5000 2600);
FORCEPROP 2 LAST SIG_NAME FLASH_LATCH_Q_N_R2
J 0
(4490 2610);
DISPLAY 0.553191 (4490 2610);
WIRE 16 -1 (5000 3550)(4300 3550);
FORCEPROP 2 LAST SIG_NAME FLASH_LATCH_Q_N_R1
J 0
(4415 3560);
DISPLAY 0.680851 (4415 3560);
WIRE 16 -1 (5000 3550)(5000 3250);
WIRE 16 -1 (3425 3550)(4100 3550);
FORCEPROP 2 LAST SIG_NAME FLASH_LATCH_Q_N_R
J 0
(3490 3560);
DISPLAY 0.680851 (3490 3560);
WIRE 16 -1 (4450 2500)(4775 2500);
FORCEPROP 2 LAST SIG_NAME NC_U55_P1
J 0
(4490 2510);
DISPLAY 0.553191 (4490 2510);
WIRE 16 -1 (2175 3300)(1725 3300);
FORCEPROP 2 LAST SIG_NAME BMC_RSTIND_N
J 0
(1715 3310);
DISPLAY 0.851064 (1715 3310);
WIRE 16 -1 (2375 3300)(2725 3300);
FORCEPROP 2 LAST SIG_NAME RD_N
J 0
(2490 3310);
DISPLAY 0.851064 (2490 3310);
WIRE 16 -1 (2725 3400)(1725 3400);
FORCEPROP 2 LAST SIG_NAME FM_FLASH_LATCH_N
J 0
(1715 3410);
DISPLAY 0.808511 (1715 3410);
WIRE 16 -1 (2725 3500)(2100 3500);
FORCEPROP 2 LAST SIG_NAME FLASH_LATCH_CP
J 0
(2140 3510);
DISPLAY 0.808511 (2140 3510);
WIRE 16 -1 (3900 1300)(4300 1300);
FORCEPROP 2 LAST SIG_NAME PU_J1_P1
J 0
(3950 1310);
DISPLAY 0.680851 (3950 1310);
WIRE 16 -1 (3900 1425)(3900 1300);
WIRE 16 -1 (350 3750)(1125 3750);
FORCEPROP 2 LAST SIG_NAME FM_FLASH_LATCH_N
J 0
(490 3760);
DISPLAY 0.851064 (490 3760);
WIRE 16 -1 (350 3800)(350 3750);
WIRE 16 -1 (3900 1200)(4300 1200);
FORCEPROP 2 LAST SIG_NAME NC_J1_P3
J 0
(3940 1210);
DISPLAY 0.702128 (3940 1210);
WIRE 16 -1 (-1025 -950)(-1800 -950);
FORCEPROP 2 LAST SIG_NAME RST_SPI_FLASH_N
J 0
(-1685 -940);
DISPLAY 0.808511 (-1685 -940);
WIRE 16 -1 (2725 3600)(2100 3600);
FORCEPROP 2 LAST SIG_NAME FLASH_LATCH_D
J 0
(2140 3610);
DISPLAY 0.808511 (2140 3610);
WIRE 16 -1 (3425 3650)(3750 3650);
FORCEPROP 2 LAST SIG_NAME NC_U54_P1
J 0
(3490 3660);
DISPLAY 0.553191 (3490 3660);
DOT 1 (-200 -275);
DOT 1 (3100 2600);
DOT 1 (5000 2600);
DOT 1 (1350 3500);
DOT 1 (3675 1900);
DOT 1 (3525 3100);
DOT 1 (2875 -950);
DOT 1 (3725 1900);
FORCENOTE
OPEN-DRAIN
(225 -1275) 0;
DISPLAY LEFT (225 -1275);
DISPLAY 1.276596 (225 -1275);
PAINT RED (225 -1275);
QUIT
